(kicad_pcb
	(version 20260206)
	(generator "pcbnew")
	(generator_version "10.0")
	(general
		(thickness 1.6)
		(legacy_teardrops no)
	)
	(paper "A4")
	(title_block
		(title "v2-pdb — ms_pdb_v2.brd")
		(comment 1 "Open CloudServer (Microsoft) / footprints 73-82 of 348")
	)
	(layers
		(0 "F.Cu" signal "TOP")
		(4 "In1.Cu" signal "GND")
		(6 "In2.Cu" signal "IN1")
		(8 "In3.Cu" signal "VCC")
		(10 "In4.Cu" signal "VCC1")
		(12 "In5.Cu" signal "IN2")
		(14 "In6.Cu" signal "GND1")
		(2 "B.Cu" signal "BOTTOM")
		(9 "F.Adhes" user "F.Adhesive")
		(11 "B.Adhes" user "B.Adhesive")
		(13 "F.Paste" user "Package Geometry/Pastemask Top")
		(15 "B.Paste" user "Package Geometry/Pastemask Bottom")
		(5 "F.SilkS" user "Ref Des/Silkscreen Top")
		(7 "B.SilkS" user "Ref Des/Silkscreen Bottom")
		(1 "F.Mask" user "Board Geometry/Soldermask Top")
		(3 "B.Mask" user "Board Geometry/Soldermask Bottom")
		(17 "Dwgs.User" user "User.Drawings")
		(19 "Cmts.User" user "User.Comments")
		(21 "Eco1.User" user "User.Eco1")
		(23 "Eco2.User" user "User.Eco2")
		(25 "Edge.Cuts" user "Board Geometry/Outline")
		(27 "Margin" user)
		(31 "F.CrtYd" user "Package Geometry/Place Bound Top")
		(29 "B.CrtYd" user "Package Geometry/Place Bound Bottom")
		(35 "F.Fab" user "Ref Des/Assembly Top")
		(33 "B.Fab" user "Ref Des/Assembly Bottom")
	)
	(footprint ""
		(layer "F.Cu")
		(at 39.705534 -105.822242 -90)
		(property "Reference" "R4"
			(at 0.830326 -2.570734 90)
			(unlocked yes)
			(layer "F.SilkS")
			(effects
				(font
					(size 0.7874 0.5842)
					(thickness 0.1524)
				)
				(justify left)
			)
		)
		(property "Value" ""
			(at 0 0 270)
			(layer "F.Fab")
			(effects
				(font
					(size 1.27 1.27)
				)
			)
		)
		(duplicate_pad_numbers_are_jumpers no)
		(fp_line
			(start -0.7874 0.4064)
			(end -0.7874 -0.4064)
			(stroke
				(width 0.1524)
				(type default)
			)
			(layer "F.SilkS")
		)
		(fp_line
			(start 0.7874 0.4064)
			(end -0.7874 0.4064)
			(stroke
				(width 0.1524)
				(type default)
			)
			(layer "F.SilkS")
		)
		(fp_line
			(start -0.7874 -0.4064)
			(end 0.7874 -0.4064)
			(stroke
				(width 0.1524)
				(type default)
			)
			(layer "F.SilkS")
		)
		(fp_line
			(start 0.7874 -0.4064)
			(end 0.7874 0.4064)
			(stroke
				(width 0.1524)
				(type default)
			)
			(layer "F.SilkS")
		)
		(fp_poly
			(pts
				(xy -0.508 0.2794) (xy -0.508 0.2286) (xy -0.635 0.2286) (xy -0.635 -0.254) (xy -0.5334 -0.254)
				(xy -0.5334 -0.2794) (xy 0.5334 -0.2794) (xy 0.5334 -0.254) (xy 0.635 -0.254) (xy 0.635 0.254) (xy 0.5334 0.254)
				(xy 0.5334 0.2794)
			)
			(stroke
				(width 0)
				(type default)
			)
			(fill no)
			(layer "F.CrtYd")
		)
		(pad "1" smd rect
			(at 0.40005 0 270)
			(size 0.4572 0.508)
			(layers "F.Cu" "F.Mask" "F.Paste")
			(net "PSU2_AD0")
		)
		(pad "2" smd rect
			(at -0.40005 0 270)
			(size 0.4572 0.508)
			(layers "F.Cu" "F.Mask" "F.Paste")
			(net "P12V_STBY")
		)
	)
	(footprint ""
		(layer "F.Cu")
		(at 50.478944 -196.729604 180)
		(property "Reference" "CE10"
			(at -4.974844 0.065278 0)
			(unlocked yes)
			(layer "F.SilkS")
			(effects
				(font
					(size 0.7874 0.5842)
					(thickness 0.1524)
				)
				(justify left)
			)
		)
		(property "Value" ""
			(at 0 0 180)
			(layer "F.Fab")
			(effects
				(font
					(size 1.27 1.27)
				)
			)
		)
		(duplicate_pad_numbers_are_jumpers no)
		(fp_line
			(start 0 -4.2672)
			(end 0 4.2672)
			(stroke
				(width 0.1524)
				(type default)
			)
			(layer "F.SilkS")
		)
		(fp_circle
			(center 0 0)
			(end -4.2672 0)
			(stroke
				(width 0.1524)
				(type default)
			)
			(fill no)
			(layer "F.SilkS")
		)
		(fp_poly
			(pts
				(arc
					(start 0 -4.2672)
					(mid 4.2672 0)
					(end 0 4.2672)
				)
			)
			(stroke
				(width 0)
				(type default)
			)
			(fill yes)
			(layer "F.SilkS")
		)
		(fp_poly
			(pts
				(xy -2.5146 -0.762) (xy -0.9906 -0.762) (xy -0.9906 0.762) (xy -2.5146 0.762)
			)
			(stroke
				(width 0)
				(type default)
			)
			(fill no)
			(layer "B.CrtYd")
		)
		(fp_poly
			(pts
				(arc
					(start 1.7526 0.762)
					(mid 2.291415 -0.538815)
					(end 0.9906 0)
				)
				(arc
					(start 0.9906 0.0254)
					(mid 1.206345 0.546255)
					(end 1.7272 0.762)
				)
			)
			(stroke
				(width 0)
				(type default)
			)
			(fill no)
			(layer "B.CrtYd")
		)
		(fp_poly
			(pts
				(arc
					(start -4.2672 0)
					(mid 4.2672 0)
					(end -4.2672 0)
				)
			)
			(stroke
				(width 0)
				(type default)
			)
			(fill no)
			(layer "F.CrtYd")
		)
		(fp_circle
			(center 0 0)
			(end -4.2672 0)
			(stroke
				(width 0.1)
				(type default)
			)
			(fill no)
			(layer "F.Fab")
		)
		(fp_text user "+"
			(at -5.846572 -1.718056 180)
			(unlocked yes)
			(layer "F.SilkS")
			(effects
				(font
					(size 1.905 1.4224)
					(thickness 0.1524)
				)
				(justify left)
			)
		)
		(fp_text user "+"
			(at -5.6642 -0.34925 180)
			(unlocked yes)
			(layer "F.Fab")
			(effects
				(font
					(size 1.905 1.4224)
					(thickness 0.000001)
				)
				(justify left)
			)
		)
		(pad "1" thru_hole rect
			(at -1.75006 0 180)
			(size 1.397 1.397)
			(drill 0.9144)
			(layers "*.Cu" "*.Mask")
			(remove_unused_layers no)
			(net "P12V")
			(clearance 0.0127)
			(thermal_gap 0.0127)
			(padstack
				(mode front_inner_back)
				(layer "Inner"
					(shape circle)
					(size 1.397 1.397)
					(clearance 0.0127)
				)
				(layer "B.Cu"
					(shape rect)
					(size 1.397 1.397)
					(clearance 0.0127)
				)
			)
		)
		(pad "2" thru_hole circle
			(at 1.75006 0 180)
			(size 1.397 1.397)
			(drill 0.9144)
			(layers "*.Cu" "*.Mask")
			(remove_unused_layers no)
			(net "GND")
			(clearance 0.0127)
			(thermal_gap 0.0127)
		)
	)
	(footprint ""
		(layer "F.Cu")
		(at 91.399868 -286.709866)
		(property "Reference" "H21"
			(at -5.1308 -5.23113 0)
			(unlocked yes)
			(layer "F.SilkS")
			(effects
				(font
					(size 0.7874 0.5842)
					(thickness 0.1524)
				)
				(justify left)
			)
		)
		(property "Value" ""
			(at 0 0 0)
			(layer "F.Fab")
			(effects
				(font
					(size 1.27 1.27)
				)
			)
		)
		(duplicate_pad_numbers_are_jumpers no)
		(fp_circle
			(center 0 0)
			(end 4.826 0)
			(stroke
				(width 0.1524)
				(type default)
			)
			(fill no)
			(layer "F.SilkS")
		)
		(fp_circle
			(center 0 0)
			(end 4.826 0)
			(stroke
				(width 0.1524)
				(type default)
			)
			(fill no)
			(layer "B.SilkS")
		)
		(fp_poly
			(pts
				(arc
					(start 0 4.0132)
					(mid 0 -4.0132)
					(end 0 4.0132)
				)
			)
			(stroke
				(width 0)
				(type default)
			)
			(fill no)
			(layer "F.CrtYd")
		)
		(pad "" np_thru_hole circle
			(at 0 0)
			(size 8.001 8.001)
			(drill 8.001)
			(layers "*.Cu" "*.Mask")
			(clearance 0.381)
			(thermal_gap 0.381)
		)
		(zone
			(layers "F.Cu" "B.Cu" "In1.Cu" "In2.Cu" "In3.Cu" "In4.Cu" "In5.Cu" "In6.Cu")
			(hatch none 0.5)
			(connect_pads
				(clearance 0)
			)
			(min_thickness 0.25)
			(keepout
				(tracks not_allowed)
				(vias allowed)
				(pads allowed)
				(copperpour not_allowed)
				(footprints allowed)
			)
			(placement
				(enabled no)
				(sheetname "")
			)
			(fill
				(thermal_gap 0.5)
				(thermal_bridge_width 0.5)
				(island_removal_mode 0)
			)
			(polygon
				(pts
					(arc
						(start 91.399868 -282.188666)
						(mid 91.399868 -291.231066)
						(end 91.399868 -282.188666)
					)
				)
			)
		)
	)
	(footprint ""
		(layer "F.Cu")
		(at 77.993494 -384.526282 180)
		(property "Reference" "R128"
			(at 1.129792 -1.375156 0)
			(unlocked yes)
			(layer "F.SilkS")
			(effects
				(font
					(size 0.7874 0.5842)
					(thickness 0.1524)
				)
				(justify left)
			)
		)
		(property "Value" ""
			(at 0 0 180)
			(layer "F.Fab")
			(effects
				(font
					(size 1.27 1.27)
				)
			)
		)
		(duplicate_pad_numbers_are_jumpers no)
		(fp_line
			(start 0.7874 0.4064)
			(end -0.7874 0.4064)
			(stroke
				(width 0.1524)
				(type default)
			)
			(layer "F.SilkS")
		)
		(fp_line
			(start 0.7874 -0.4064)
			(end 0.7874 0.4064)
			(stroke
				(width 0.1524)
				(type default)
			)
			(layer "F.SilkS")
		)
		(fp_line
			(start -0.7874 0.4064)
			(end -0.7874 -0.4064)
			(stroke
				(width 0.1524)
				(type default)
			)
			(layer "F.SilkS")
		)
		(fp_line
			(start -0.7874 -0.4064)
			(end 0.7874 -0.4064)
			(stroke
				(width 0.1524)
				(type default)
			)
			(layer "F.SilkS")
		)
		(fp_poly
			(pts
				(xy -0.508 0.2794) (xy -0.508 0.2286) (xy -0.635 0.2286) (xy -0.635 -0.254) (xy -0.5334 -0.254)
				(xy -0.5334 -0.2794) (xy 0.5334 -0.2794) (xy 0.5334 -0.254) (xy 0.635 -0.254) (xy 0.635 0.254) (xy 0.5334 0.254)
				(xy 0.5334 0.2794)
			)
			(stroke
				(width 0)
				(type default)
			)
			(fill no)
			(layer "F.CrtYd")
		)
		(pad "1" smd rect
			(at 0.40005 0 180)
			(size 0.4572 0.508)
			(layers "F.Cu" "F.Mask" "F.Paste")
			(net "PSU5_REMOTE_R2_N")
		)
		(pad "2" smd rect
			(at -0.40005 0 180)
			(size 0.4572 0.508)
			(layers "F.Cu" "F.Mask" "F.Paste")
			(net "GND")
		)
	)
	(footprint ""
		(layer "F.Cu")
		(at 80.947006 -297.892216 180)
		(property "Reference" "R123"
			(at 1.088644 1.215136 0)
			(unlocked yes)
			(layer "F.SilkS")
			(effects
				(font
					(size 0.7874 0.5842)
					(thickness 0.1524)
				)
				(justify left)
			)
		)
		(property "Value" ""
			(at 0 0 180)
			(layer "F.Fab")
			(effects
				(font
					(size 1.27 1.27)
				)
			)
		)
		(duplicate_pad_numbers_are_jumpers no)
		(fp_line
			(start 0.7874 0.4064)
			(end -0.7874 0.4064)
			(stroke
				(width 0.1524)
				(type default)
			)
			(layer "F.SilkS")
		)
		(fp_line
			(start 0.7874 -0.4064)
			(end 0.7874 0.4064)
			(stroke
				(width 0.1524)
				(type default)
			)
			(layer "F.SilkS")
		)
		(fp_line
			(start -0.7874 0.4064)
			(end -0.7874 -0.4064)
			(stroke
				(width 0.1524)
				(type default)
			)
			(layer "F.SilkS")
		)
		(fp_line
			(start -0.7874 -0.4064)
			(end 0.7874 -0.4064)
			(stroke
				(width 0.1524)
				(type default)
			)
			(layer "F.SilkS")
		)
		(fp_poly
			(pts
				(xy -0.508 0.2794) (xy -0.508 0.2286) (xy -0.635 0.2286) (xy -0.635 -0.254) (xy -0.5334 -0.254)
				(xy -0.5334 -0.2794) (xy 0.5334 -0.2794) (xy 0.5334 -0.254) (xy 0.635 -0.254) (xy 0.635 0.254) (xy 0.5334 0.254)
				(xy 0.5334 0.2794)
			)
			(stroke
				(width 0)
				(type default)
			)
			(fill no)
			(layer "F.CrtYd")
		)
		(pad "1" smd rect
			(at 0.40005 0 180)
			(size 0.4572 0.508)
			(layers "F.Cu" "F.Mask" "F.Paste")
			(net "PSU4_REMOTE_R2_P")
		)
		(pad "2" smd rect
			(at -0.40005 0 180)
			(size 0.4572 0.508)
			(layers "F.Cu" "F.Mask" "F.Paste")
			(net "P12V")
		)
	)
	(footprint ""
		(layer "F.Cu")
		(at 80.662018 -18.749772 -90)
		(property "Reference" "C6"
			(at -1.75133 0.018796 90)
			(unlocked yes)
			(layer "F.SilkS")
			(effects
				(font
					(size 0.7874 0.5842)
					(thickness 0.1524)
				)
				(justify left)
			)
		)
		(property "Value" ""
			(at 0 0 270)
			(layer "F.Fab")
			(effects
				(font
					(size 1.27 1.27)
				)
			)
		)
		(duplicate_pad_numbers_are_jumpers no)
		(fp_line
			(start -0.7874 0.4064)
			(end -0.7874 -0.4064)
			(stroke
				(width 0.1524)
				(type default)
			)
			(layer "F.SilkS")
		)
		(fp_line
			(start 0.7874 0.4064)
			(end -0.7874 0.4064)
			(stroke
				(width 0.1524)
				(type default)
			)
			(layer "F.SilkS")
		)
		(fp_line
			(start 0 0.381)
			(end 0 -0.381)
			(stroke
				(width 0.1524)
				(type default)
			)
			(layer "F.SilkS")
		)
		(fp_line
			(start -0.7874 -0.4064)
			(end 0.7874 -0.4064)
			(stroke
				(width 0.1524)
				(type default)
			)
			(layer "F.SilkS")
		)
		(fp_line
			(start 0.7874 -0.4064)
			(end 0.7874 0.4064)
			(stroke
				(width 0.1524)
				(type default)
			)
			(layer "F.SilkS")
		)
		(fp_poly
			(pts
				(xy -0.5334 0.254) (xy -0.635 0.254) (xy -0.635 0.2286) (xy -0.635 -0.254) (xy -0.5334 -0.254) (xy -0.5334 -0.2794)
				(xy 0.5334 -0.2794) (xy 0.5334 -0.254) (xy 0.635 -0.254) (xy 0.635 0.254) (xy 0.5334 0.254) (xy 0.5334 0.2794)
				(xy -0.508 0.2794) (xy -0.5334 0.2794)
			)
			(stroke
				(width 0)
				(type default)
			)
			(fill no)
			(layer "F.CrtYd")
		)
		(pad "1" smd rect
			(at 0.40005 0 270)
			(size 0.4572 0.508)
			(layers "F.Cu" "F.Mask" "F.Paste")
			(net "P12V")
		)
		(pad "2" smd rect
			(at -0.40005 0 270)
			(size 0.4572 0.508)
			(layers "F.Cu" "F.Mask" "F.Paste")
			(net "GND")
		)
	)
	(footprint ""
		(layer "F.Cu")
		(at 13.463778 -324.01002 180)
		(property "Reference" "R146"
			(at -1.597406 -0.03556 0)
			(unlocked yes)
			(layer "F.SilkS")
			(effects
				(font
					(size 0.7874 0.5842)
					(thickness 0.1524)
				)
				(justify left)
			)
		)
		(property "Value" ""
			(at 0 0 180)
			(layer "F.Fab")
			(effects
				(font
					(size 1.27 1.27)
				)
			)
		)
		(duplicate_pad_numbers_are_jumpers no)
		(fp_line
			(start 0.7874 0.4064)
			(end -0.7874 0.4064)
			(stroke
				(width 0.1524)
				(type default)
			)
			(layer "F.SilkS")
		)
		(fp_line
			(start 0.7874 -0.4064)
			(end 0.7874 0.4064)
			(stroke
				(width 0.1524)
				(type default)
			)
			(layer "F.SilkS")
		)
		(fp_line
			(start -0.7874 0.4064)
			(end -0.7874 -0.4064)
			(stroke
				(width 0.1524)
				(type default)
			)
			(layer "F.SilkS")
		)
		(fp_line
			(start -0.7874 -0.4064)
			(end 0.7874 -0.4064)
			(stroke
				(width 0.1524)
				(type default)
			)
			(layer "F.SilkS")
		)
		(fp_poly
			(pts
				(xy -0.508 0.2794) (xy -0.508 0.2286) (xy -0.635 0.2286) (xy -0.635 -0.254) (xy -0.5334 -0.254)
				(xy -0.5334 -0.2794) (xy 0.5334 -0.2794) (xy 0.5334 -0.254) (xy 0.635 -0.254) (xy 0.635 0.254) (xy 0.5334 0.254)
				(xy 0.5334 0.2794)
			)
			(stroke
				(width 0)
				(type default)
			)
			(fill no)
			(layer "F.CrtYd")
		)
		(pad "1" smd rect
			(at 0.40005 0 180)
			(size 0.4572 0.508)
			(layers "F.Cu" "F.Mask" "F.Paste")
			(net "FAN5_TACH")
		)
		(pad "2" smd rect
			(at -0.40005 0 180)
			(size 0.4572 0.508)
			(layers "F.Cu" "F.Mask" "F.Paste")
			(net "P12V")
		)
	)
	(footprint ""
		(layer "F.Cu")
		(at 70.555104 -127.633476 90)
		(property "Reference" "C25"
			(at 1.102868 0.090932 90)
			(unlocked yes)
			(layer "F.SilkS")
			(effects
				(font
					(size 0.7874 0.5842)
					(thickness 0.1524)
				)
				(justify left)
			)
		)
		(property "Value" ""
			(at 0 0 90)
			(layer "F.Fab")
			(effects
				(font
					(size 1.27 1.27)
				)
			)
		)
		(duplicate_pad_numbers_are_jumpers no)
		(fp_line
			(start 0.7874 -0.4064)
			(end 0.7874 0.4064)
			(stroke
				(width 0.1524)
				(type default)
			)
			(layer "F.SilkS")
		)
		(fp_line
			(start -0.7874 -0.4064)
			(end 0.7874 -0.4064)
			(stroke
				(width 0.1524)
				(type default)
			)
			(layer "F.SilkS")
		)
		(fp_line
			(start 0 0.381)
			(end 0 -0.381)
			(stroke
				(width 0.1524)
				(type default)
			)
			(layer "F.SilkS")
		)
		(fp_line
			(start 0.7874 0.4064)
			(end -0.7874 0.4064)
			(stroke
				(width 0.1524)
				(type default)
			)
			(layer "F.SilkS")
		)
		(fp_line
			(start -0.7874 0.4064)
			(end -0.7874 -0.4064)
			(stroke
				(width 0.1524)
				(type default)
			)
			(layer "F.SilkS")
		)
		(fp_poly
			(pts
				(xy -0.5334 0.254) (xy -0.635 0.254) (xy -0.635 0.2286) (xy -0.635 -0.254) (xy -0.5334 -0.254) (xy -0.5334 -0.2794)
				(xy 0.5334 -0.2794) (xy 0.5334 -0.254) (xy 0.635 -0.254) (xy 0.635 0.254) (xy 0.5334 0.254) (xy 0.5334 0.2794)
				(xy -0.508 0.2794) (xy -0.5334 0.2794)
			)
			(stroke
				(width 0)
				(type default)
			)
			(fill no)
			(layer "F.CrtYd")
		)
		(pad "1" smd rect
			(at 0.40005 0 90)
			(size 0.4572 0.508)
			(layers "F.Cu" "F.Mask" "F.Paste")
			(net "P12V")
		)
		(pad "2" smd rect
			(at -0.40005 0 90)
			(size 0.4572 0.508)
			(layers "F.Cu" "F.Mask" "F.Paste")
			(net "GND")
		)
	)
	(footprint ""
		(layer "F.Cu")
		(at 68.246244 -216.615772 90)
		(property "Reference" "C41"
			(at 1.187196 -0.117856 90)
			(unlocked yes)
			(layer "F.SilkS")
			(effects
				(font
					(size 0.7874 0.5842)
					(thickness 0.1524)
				)
				(justify left)
			)
		)
		(property "Value" ""
			(at 0 0 90)
			(layer "F.Fab")
			(effects
				(font
					(size 1.27 1.27)
				)
			)
		)
		(duplicate_pad_numbers_are_jumpers no)
		(fp_line
			(start 0.7874 -0.4064)
			(end 0.7874 0.4064)
			(stroke
				(width 0.1524)
				(type default)
			)
			(layer "F.SilkS")
		)
		(fp_line
			(start -0.7874 -0.4064)
			(end 0.7874 -0.4064)
			(stroke
				(width 0.1524)
				(type default)
			)
			(layer "F.SilkS")
		)
		(fp_line
			(start 0 0.381)
			(end 0 -0.381)
			(stroke
				(width 0.1524)
				(type default)
			)
			(layer "F.SilkS")
		)
		(fp_line
			(start 0.7874 0.4064)
			(end -0.7874 0.4064)
			(stroke
				(width 0.1524)
				(type default)
			)
			(layer "F.SilkS")
		)
		(fp_line
			(start -0.7874 0.4064)
			(end -0.7874 -0.4064)
			(stroke
				(width 0.1524)
				(type default)
			)
			(layer "F.SilkS")
		)
		(fp_poly
			(pts
				(xy -0.5334 0.254) (xy -0.635 0.254) (xy -0.635 0.2286) (xy -0.635 -0.254) (xy -0.5334 -0.254) (xy -0.5334 -0.2794)
				(xy 0.5334 -0.2794) (xy 0.5334 -0.254) (xy 0.635 -0.254) (xy 0.635 0.254) (xy 0.5334 0.254) (xy 0.5334 0.2794)
				(xy -0.508 0.2794) (xy -0.5334 0.2794)
			)
			(stroke
				(width 0)
				(type default)
			)
			(fill no)
			(layer "F.CrtYd")
		)
		(pad "1" smd rect
			(at 0.40005 0 90)
			(size 0.4572 0.508)
			(layers "F.Cu" "F.Mask" "F.Paste")
			(net "P12V")
		)
		(pad "2" smd rect
			(at -0.40005 0 90)
			(size 0.4572 0.508)
			(layers "F.Cu" "F.Mask" "F.Paste")
			(net "GND")
		)
	)
	(footprint ""
		(layer "F.Cu")
		(at 72.953626 -472.101672 180)
		(property "Reference" "R132"
			(at 1.12141 -1.136904 0)
			(unlocked yes)
			(layer "F.SilkS")
			(effects
				(font
					(size 0.7874 0.5842)
					(thickness 0.1524)
				)
				(justify left)
			)
		)
		(property "Value" ""
			(at 0 0 180)
			(layer "F.Fab")
			(effects
				(font
					(size 1.27 1.27)
				)
			)
		)
		(duplicate_pad_numbers_are_jumpers no)
		(fp_line
			(start 0.7874 0.4064)
			(end -0.7874 0.4064)
			(stroke
				(width 0.1524)
				(type default)
			)
			(layer "F.SilkS")
		)
		(fp_line
			(start 0.7874 -0.4064)
			(end 0.7874 0.4064)
			(stroke
				(width 0.1524)
				(type default)
			)
			(layer "F.SilkS")
		)
		(fp_line
			(start -0.7874 0.4064)
			(end -0.7874 -0.4064)
			(stroke
				(width 0.1524)
				(type default)
			)
			(layer "F.SilkS")
		)
		(fp_line
			(start -0.7874 -0.4064)
			(end 0.7874 -0.4064)
			(stroke
				(width 0.1524)
				(type default)
			)
			(layer "F.SilkS")
		)
		(fp_poly
			(pts
				(xy -0.508 0.2794) (xy -0.508 0.2286) (xy -0.635 0.2286) (xy -0.635 -0.254) (xy -0.5334 -0.254)
				(xy -0.5334 -0.2794) (xy 0.5334 -0.2794) (xy 0.5334 -0.254) (xy 0.635 -0.254) (xy 0.635 0.254) (xy 0.5334 0.254)
				(xy 0.5334 0.2794)
			)
			(stroke
				(width 0)
				(type default)
			)
			(fill no)
			(layer "F.CrtYd")
		)
		(pad "1" smd rect
			(at 0.40005 0 180)
			(size 0.4572 0.508)
			(layers "F.Cu" "F.Mask" "F.Paste")
			(net "PSU6_REMOTE_R2_N")
		)
		(pad "2" smd rect
			(at -0.40005 0 180)
			(size 0.4572 0.508)
			(layers "F.Cu" "F.Mask" "F.Paste")
			(net "GND")
		)
	)
)
